# BASEBOARD_FAB2 (Tioga Pass) — schematic netlist excerpt (pin names and nets, part order shuffled) for the footprints in the layout excerpt that follows; sources: Cadence DE-HDL packaged netlist, KiCad conversion of Wiwynn_Tioga_Pass_MB.brd

C25W94  CAP  1.0UF 16V 10% X6S  pkg 0402  page 254 : A = P3V3_STBY ; B = GND
C5G71  CAP_A  22.0UF 4V 20% X6S  pkg 0603V  page 242 : A = PVDDQ_DEF ; B = GND
C7L5  CAP_A  47UF 4V 20% X5R  pkg 0603V  page 228 : A = PVDDQ_KLM ; B = GND

(kicad_pcb
	(version 20260206)
	(generator "pcbnew")
	(generator_version "10.0")
	(general
		(thickness 1.6)
		(legacy_teardrops no)
	)
	(paper "A4")
	(title_block
		(title "Wiwynn_Tioga_Pass_MB.brd")
		(comment 1 "Tioga Pass / footprints 3068-3070 of 4770")
	)
	(layers
		(0 "F.Cu" signal "TOP")
		(4 "In1.Cu" signal "L2GND")
		(6 "In2.Cu" signal "L3")
		(8 "In3.Cu" signal "L4GND")
		(10 "In4.Cu" signal "L5")
		(12 "In5.Cu" signal "L6GND")
		(14 "In6.Cu" signal "L7VCC")
		(16 "In7.Cu" signal "L8VCC")
		(18 "In8.Cu" signal "L9GND")
		(20 "In9.Cu" signal "L10")
		(22 "In10.Cu" signal "L11GND")
		(24 "In11.Cu" signal "L12")
		(26 "In12.Cu" signal "L13GND")
		(2 "B.Cu" signal "BOTTOM")
		(9 "F.Adhes" user "F.Adhesive")
		(11 "B.Adhes" user "B.Adhesive")
		(13 "F.Paste" user "Package Geometry/Pastemask Top")
		(15 "B.Paste" user "Package Geometry/Pastemask Bottom")
		(5 "F.SilkS" user "Ref Des/Silkscreen Top")
		(7 "B.SilkS" user "Ref Des/Silkscreen Bottom")
		(1 "F.Mask" user "Board Geometry/Soldermask Top")
		(3 "B.Mask" user "Board Geometry/Soldermask Bottom")
		(17 "Dwgs.User" user "User.Drawings")
		(19 "Cmts.User" user "User.Comments")
		(21 "Eco1.User" user "User.Eco1")
		(23 "Eco2.User" user "User.Eco2")
		(25 "Edge.Cuts" user "Board Geometry/Outline")
		(27 "Margin" user)
		(31 "F.CrtYd" user "Package Geometry/Place Bound Top")
		(29 "B.CrtYd" user "Package Geometry/Place Bound Bottom")
		(35 "F.Fab" user "Ref Des/Assembly Top")
		(33 "B.Fab" user "Ref Des/Assembly Bottom")
	)
	(footprint ""
		(layer "B.Cu")
		(at 107.8611 -145.0086 90)
		(property "Reference" "C7L5"
			(at -1.848866 0.752348 90)
			(unlocked yes)
			(layer "B.SilkS")
			(effects
				(font
					(size 1.27 0.9652)
					(thickness 0.1524)
				)
				(justify mirror)
			)
		)
		(property "Value" ""
			(at 0 0 90)
			(layer "B.Fab")
			(effects
				(font
					(size 1.27 1.27)
				)
				(justify mirror)
			)
		)
		(duplicate_pad_numbers_are_jumpers no)
		(fp_rect
			(start 0.500126 1.598422)
			(end -0.500126 -0.201422)
			(stroke
				(width 0)
				(type default)
			)
			(fill no)
			(layer "B.CrtYd")
		)
		(fp_line
			(start 0.500126 -0.201422)
			(end -0.500126 -0.201422)
			(stroke
				(width 0.1)
				(type default)
			)
			(layer "B.Fab")
		)
		(fp_line
			(start -0.500126 -0.201422)
			(end -0.500126 1.598422)
			(stroke
				(width 0.1)
				(type default)
			)
			(layer "B.Fab")
		)
		(fp_line
			(start 0.500126 1.598422)
			(end 0.500126 -0.201422)
			(stroke
				(width 0.1)
				(type default)
			)
			(layer "B.Fab")
		)
		(fp_line
			(start -0.500126 1.598422)
			(end 0.500126 1.598422)
			(stroke
				(width 0.1)
				(type default)
			)
			(layer "B.Fab")
		)
		(pad "1" smd rect
			(at 0 0)
			(size 0.889 0.9906)
			(layers "B.Cu" "B.Mask" "B.Paste")
			(net "PVDDQ_KLM")
		)
		(pad "2" smd rect
			(at 0 1.397)
			(size 0.889 0.9906)
			(layers "B.Cu" "B.Mask" "B.Paste")
			(net "GND")
		)
		(zone
			(layer "B.Cu")
			(hatch none 0.5)
			(connect_pads
				(clearance 0)
			)
			(min_thickness 0.25)
			(keepout
				(tracks not_allowed)
				(vias allowed)
				(pads allowed)
				(copperpour not_allowed)
				(footprints allowed)
			)
			(placement
				(enabled no)
				(sheetname "")
			)
			(fill
				(thermal_gap 0.5)
				(thermal_bridge_width 0.5)
				(island_removal_mode 0)
			)
			(polygon
				(pts
					(xy 108.8136 -145.5039) (xy 108.3056 -145.5039) (xy 108.3056 -144.5133) (xy 108.8136 -144.5133)
				)
			)
		)
		(zone
			(layer "B.Cu")
			(hatch none 0.5)
			(connect_pads
				(clearance 0)
			)
			(min_thickness 0.25)
			(keepout
				(tracks allowed)
				(vias not_allowed)
				(pads allowed)
				(copperpour not_allowed)
				(footprints allowed)
			)
			(placement
				(enabled no)
				(sheetname "")
			)
			(fill
				(thermal_gap 0.5)
				(thermal_bridge_width 0.5)
				(island_removal_mode 0)
			)
			(polygon
				(pts
					(xy 108.8136 -145.5039) (xy 108.3056 -145.5039) (xy 108.3056 -144.5133) (xy 108.8136 -144.5133)
				)
			)
		)
	)
	(footprint ""
		(layer "B.Cu")
		(at 437.0197 -149.7965)
		(property "Reference" "C25W94"
			(at 0.8382 -0.67818 0)
			(unlocked yes)
			(layer "B.SilkS")
			(effects
				(font
					(size 0.4064 0.254)
					(thickness 0.1524)
				)
				(justify left mirror)
			)
		)
		(property "Value" ""
			(at 0 0 0)
			(layer "B.Fab")
			(effects
				(font
					(size 1.27 1.27)
				)
				(justify mirror)
			)
		)
		(duplicate_pad_numbers_are_jumpers no)
		(fp_poly
			(pts
				(xy -0.3048 -0.1016) (xy -0.3048 0.9906) (xy 0.3048 0.9906) (xy 0.3048 -0.1016)
			)
			(stroke
				(width 0)
				(type default)
			)
			(fill no)
			(layer "B.CrtYd")
		)
		(fp_line
			(start -0.3048 -0.1016)
			(end 0.3048 -0.1016)
			(stroke
				(width 0.1)
				(type default)
			)
			(layer "B.Fab")
		)
		(fp_line
			(start -0.3048 0.9906)
			(end -0.3048 -0.1016)
			(stroke
				(width 0.1)
				(type default)
			)
			(layer "B.Fab")
		)
		(fp_line
			(start 0.3048 -0.1016)
			(end 0.3048 0.9906)
			(stroke
				(width 0.1)
				(type default)
			)
			(layer "B.Fab")
		)
		(fp_line
			(start 0.3048 0.9906)
			(end -0.3048 0.9906)
			(stroke
				(width 0.1)
				(type default)
			)
			(layer "B.Fab")
		)
		(pad "1" smd rect
			(at 0 0 180)
			(size 0.508 0.508)
			(layers "B.Cu" "B.Mask" "B.Paste")
			(net "P3V3_STBY")
		)
		(pad "2" smd rect
			(at 0 0.889 180)
			(size 0.508 0.508)
			(layers "B.Cu" "B.Mask" "B.Paste")
			(net "GND")
		)
		(zone
			(layer "B.Cu")
			(hatch none 0.5)
			(connect_pads
				(clearance 0)
			)
			(min_thickness 0.25)
			(keepout
				(tracks allowed)
				(vias not_allowed)
				(pads allowed)
				(copperpour not_allowed)
				(footprints allowed)
			)
			(placement
				(enabled no)
				(sheetname "")
			)
			(fill
				(thermal_gap 0.5)
				(thermal_bridge_width 0.5)
				(island_removal_mode 0)
			)
			(polygon
				(pts
					(xy 437.2737 -149.5425) (xy 436.7657 -149.5425) (xy 436.7657 -149.1615) (xy 437.2737 -149.1615)
				)
			)
		)
		(zone
			(layer "B.Cu")
			(hatch none 0.5)
			(connect_pads
				(clearance 0)
			)
			(min_thickness 0.25)
			(keepout
				(tracks not_allowed)
				(vias allowed)
				(pads allowed)
				(copperpour not_allowed)
				(footprints allowed)
			)
			(placement
				(enabled no)
				(sheetname "")
			)
			(fill
				(thermal_gap 0.5)
				(thermal_bridge_width 0.5)
				(island_removal_mode 0)
			)
			(polygon
				(pts
					(xy 437.2737 -149.1615) (xy 436.7657 -149.1615) (xy 436.7657 -149.5425) (xy 437.2737 -149.5425)
				)
			)
		)
	)
	(footprint ""
		(layer "B.Cu")
		(at 272.861532 -149.8092 90)
		(property "Reference" "C5G71"
			(at -1.14681 0.76708 180)
			(unlocked yes)
			(layer "B.SilkS")
			(effects
				(font
					(size 0.7874 0.5842)
					(thickness 0.1524)
				)
				(justify mirror)
			)
		)
		(property "Value" ""
			(at 0 0 90)
			(layer "B.Fab")
			(effects
				(font
					(size 1.27 1.27)
				)
				(justify mirror)
			)
		)
		(duplicate_pad_numbers_are_jumpers no)
		(fp_rect
			(start -0.4953 -0.2032)
			(end 0.4953 1.6002)
			(stroke
				(width 0)
				(type default)
			)
			(fill no)
			(layer "B.CrtYd")
		)
		(fp_line
			(start 0.4953 -0.2032)
			(end -0.4953 -0.2032)
			(stroke
				(width 0.1)
				(type default)
			)
			(layer "B.Fab")
		)
		(fp_line
			(start -0.4953 -0.2032)
			(end -0.4953 1.6002)
			(stroke
				(width 0.1)
				(type default)
			)
			(layer "B.Fab")
		)
		(fp_line
			(start 0.4953 1.6002)
			(end 0.4953 -0.2032)
			(stroke
				(width 0.1)
				(type default)
			)
			(layer "B.Fab")
		)
		(fp_line
			(start -0.4953 1.6002)
			(end 0.4953 1.6002)
			(stroke
				(width 0.1)
				(type default)
			)
			(layer "B.Fab")
		)
		(pad "1" smd rect
			(at 0 0 270)
			(size 0.762 0.889)
			(layers "B.Cu" "B.Mask" "B.Paste")
			(net "PVDDQ_DEF")
		)
		(pad "2" smd rect
			(at 0 1.397 270)
			(size 0.762 0.889)
			(layers "B.Cu" "B.Mask" "B.Paste")
			(net "GND")
		)
		(zone
			(layer "B.Cu")
			(hatch none 0.5)
			(connect_pads
				(clearance 0)
			)
			(min_thickness 0.25)
			(keepout
				(tracks not_allowed)
				(vias allowed)
				(pads allowed)
				(copperpour not_allowed)
				(footprints allowed)
			)
			(placement
				(enabled no)
				(sheetname "")
			)
			(fill
				(thermal_gap 0.5)
				(thermal_bridge_width 0.5)
				(island_removal_mode 0)
			)
			(polygon
				(pts
					(xy 273.306032 -149.4282) (xy 273.814032 -149.4282) (xy 273.814032 -150.1902) (xy 273.306032 -150.1902)
				)
			)
		)
	)
)
